(kicad_pcb
	(version 20260206)
	(generator "pcbnew")
	(generator_version "10.0")
	(general
		(thickness 1.6)
		(legacy_teardrops no)
	)
	(paper "A4")
	(title_block
		(title "01162023_DA0F0TEBIF0_F0T_Expander_BD_F_brd_V02_OCP.brd")
		(comment 1 "Grand Teton / footprints 7231-7238 of 9728")
	)
	(layers
		(0 "F.Cu" signal "TOP")
		(4 "In1.Cu" signal "GND")
		(6 "In2.Cu" signal "VCC")
		(8 "In3.Cu" signal "VCC1")
		(10 "In4.Cu" signal "GND1")
		(12 "In5.Cu" signal "IN1")
		(14 "In6.Cu" signal "GND2")
		(16 "In7.Cu" signal "IN2")
		(18 "In8.Cu" signal "GND3")
		(20 "In9.Cu" signal "IN3")
		(22 "In10.Cu" signal "GND4")
		(24 "In11.Cu" signal "IN4")
		(26 "In12.Cu" signal "GND5")
		(28 "In13.Cu" signal "IN5")
		(30 "In14.Cu" signal "GND6")
		(32 "In15.Cu" signal "IN6")
		(34 "In16.Cu" signal "GND7")
		(2 "B.Cu" signal "BOTTOM")
		(9 "F.Adhes" user "F.Adhesive")
		(11 "B.Adhes" user "B.Adhesive")
		(13 "F.Paste" user "Package Geometry/Pastemask Top")
		(15 "B.Paste" user "Package Geometry/Pastemask Bottom")
		(5 "F.SilkS" user "Ref Des/Silkscreen Top")
		(7 "B.SilkS" user "Ref Des/Silkscreen Bottom")
		(1 "F.Mask" user "Board Geometry/Soldermask Top")
		(3 "B.Mask" user "Board Geometry/Soldermask Bottom")
		(17 "Dwgs.User" user "User.Drawings")
		(19 "Cmts.User" user "User.Comments")
		(21 "Eco1.User" user "User.Eco1")
		(23 "Eco2.User" user "User.Eco2")
		(25 "Edge.Cuts" user "Board Geometry/Outline")
		(27 "Margin" user)
		(31 "F.CrtYd" user "Package Geometry/Place Bound Top")
		(29 "B.CrtYd" user "Package Geometry/Place Bound Bottom")
		(35 "F.Fab" user "Ref Des/Assembly Top")
		(33 "B.Fab" user "Ref Des/Assembly Bottom")
	)
	(footprint ""
		(layer "B.Cu")
		(at 133.731 -283.818584 90)
		(property "Reference" "PR111"
			(at 0 0 90)
			(layer "B.SilkS")
			(hide yes)
			(effects
				(font
					(size 1.27 1.27)
				)
				(justify mirror)
			)
		)
		(property "Value" ""
			(at 0 0 90)
			(layer "B.Fab")
			(effects
				(font
					(size 1.27 1.27)
				)
				(justify mirror)
			)
		)
		(duplicate_pad_numbers_are_jumpers no)
		(fp_line
			(start 0.7874 -0.4064)
			(end -0.7874 -0.4064)
			(stroke
				(width 0.1524)
				(type default)
			)
			(layer "B.SilkS")
		)
		(fp_line
			(start -0.7874 -0.4064)
			(end -0.7874 0.4064)
			(stroke
				(width 0.1524)
				(type default)
			)
			(layer "B.SilkS")
		)
		(fp_line
			(start 0.7874 0.4064)
			(end 0.7874 -0.4064)
			(stroke
				(width 0.1524)
				(type default)
			)
			(layer "B.SilkS")
		)
		(fp_line
			(start -0.7874 0.4064)
			(end 0.7874 0.4064)
			(stroke
				(width 0.1524)
				(type default)
			)
			(layer "B.SilkS")
		)
		(fp_line
			(start 0.67945 -0.305054)
			(end 0.12065 -0.305054)
			(stroke
				(width 0.1)
				(type default)
			)
			(layer "B.Fab")
		)
		(fp_line
			(start 0.12065 -0.305054)
			(end 0.12065 -0.2794)
			(stroke
				(width 0.1)
				(type default)
			)
			(layer "B.Fab")
		)
		(fp_line
			(start -0.12065 -0.3048)
			(end -0.67945 -0.3048)
			(stroke
				(width 0.1)
				(type default)
			)
			(layer "B.Fab")
		)
		(fp_line
			(start -0.67945 -0.3048)
			(end -0.67945 0.3048)
			(stroke
				(width 0.1)
				(type default)
			)
			(layer "B.Fab")
		)
		(fp_line
			(start 0.12065 -0.2794)
			(end -0.12065 -0.2794)
			(stroke
				(width 0.1)
				(type default)
			)
			(layer "B.Fab")
		)
		(fp_line
			(start -0.12065 -0.2794)
			(end -0.12065 -0.3048)
			(stroke
				(width 0.1)
				(type default)
			)
			(layer "B.Fab")
		)
		(fp_line
			(start 0.12065 0.2794)
			(end 0.12065 0.3048)
			(stroke
				(width 0.1)
				(type default)
			)
			(layer "B.Fab")
		)
		(fp_line
			(start -0.120396 0.2794)
			(end 0.12065 0.2794)
			(stroke
				(width 0.1)
				(type default)
			)
			(layer "B.Fab")
		)
		(fp_line
			(start 0.67945 0.3048)
			(end 0.67945 -0.305054)
			(stroke
				(width 0.1)
				(type default)
			)
			(layer "B.Fab")
		)
		(fp_line
			(start 0.12065 0.3048)
			(end 0.67945 0.3048)
			(stroke
				(width 0.1)
				(type default)
			)
			(layer "B.Fab")
		)
		(fp_line
			(start -0.120396 0.3048)
			(end -0.120396 0.2794)
			(stroke
				(width 0.1)
				(type default)
			)
			(layer "B.Fab")
		)
		(fp_line
			(start -0.67945 0.3048)
			(end -0.120396 0.3048)
			(stroke
				(width 0.1)
				(type default)
			)
			(layer "B.Fab")
		)
		(pad "1" smd circle
			(at 0.40005 0 270)
			(size 0 0)
			(layers "B.Cu" "B.Mask" "B.Paste")
			(net "P0V8_PEX1_PVCC")
		)
		(pad "2" smd circle
			(at -0.40005 0 270)
			(size 0 0)
			(layers "B.Cu" "B.Mask" "B.Paste")
			(net "P0V8_PEX1_VCC2")
		)
	)
	(footprint ""
		(layer "B.Cu")
		(at 57.274968 -293.99992 -90)
		(property "Reference" "C1149"
			(at 0 0 90)
			(layer "B.SilkS")
			(hide yes)
			(effects
				(font
					(size 1.27 1.27)
				)
				(justify mirror)
			)
		)
		(property "Value" ""
			(at 0 0 90)
			(layer "B.Fab")
			(effects
				(font
					(size 1.27 1.27)
				)
				(justify mirror)
			)
		)
		(duplicate_pad_numbers_are_jumpers no)
		(fp_line
			(start -0.299974 0.150114)
			(end 0.299974 0.150114)
			(stroke
				(width 0.1)
				(type default)
			)
			(layer "B.Fab")
		)
		(fp_line
			(start 0.299974 0.150114)
			(end 0.299974 -0.150114)
			(stroke
				(width 0.1)
				(type default)
			)
			(layer "B.Fab")
		)
		(fp_line
			(start -0.299974 -0.150114)
			(end -0.299974 0.150114)
			(stroke
				(width 0.1)
				(type default)
			)
			(layer "B.Fab")
		)
		(fp_line
			(start 0.299974 -0.150114)
			(end -0.299974 -0.150114)
			(stroke
				(width 0.1)
				(type default)
			)
			(layer "B.Fab")
		)
		(pad "1" smd rect
			(at 0.2667 0 90)
			(size 0.3048 0.381)
			(layers "B.Cu" "B.Mask" "B.Paste")
			(net "P0V8_PEX0")
		)
		(pad "2" smd rect
			(at -0.2667 0 90)
			(size 0.3048 0.381)
			(layers "B.Cu" "B.Mask" "B.Paste")
			(net "GND")
		)
	)
	(footprint ""
		(layer "B.Cu")
		(at 14.312392 -441.437014)
		(property "Reference" "X62"
			(at -0.9017 -2.08407 180)
			(unlocked yes)
			(layer "B.SilkS")
			(effects
				(font
					(size 0.7874 0.5842)
					(thickness 0.1524)
				)
				(justify mirror)
			)
		)
		(property "Value" ""
			(at 0 0 0)
			(layer "B.Fab")
			(effects
				(font
					(size 1.27 1.27)
				)
				(justify mirror)
			)
		)
		(property "Device Type" "TP_TDR_4P_FTS_MPKT4_H025P0200_IO_TP15_TP_TDR_4P_DIP"
			(at -1.30175 1.27 270)
			(unlocked yes)
			(layer "B.Fab")
			(hide yes)
			(effects
				(font
					(size 0.635 0.4064)
					(thickness 0.1524)
				)
				(justify mirror)
			)
		)
		(property "User Part Number" "TP15"
			(at -1.30175 1.27 270)
			(unlocked yes)
			(layer "Cmts.User")
			(hide yes)
			(effects
				(font
					(size 0.635 0.4064)
					(thickness 0.1524)
				)
				(justify mirror)
			)
		)
		(duplicate_pad_numbers_are_jumpers no)
		(fp_line
			(start -2.54 -1.27)
			(end 0 -1.27)
			(stroke
				(width 0.1524)
				(type default)
			)
			(layer "B.SilkS")
		)
		(fp_line
			(start -2.54 -1.1303)
			(end -2.54 -1.27)
			(stroke
				(width 0.1524)
				(type default)
			)
			(layer "B.SilkS")
		)
		(fp_line
			(start -2.54 1.4097)
			(end -2.54 1.1303)
			(stroke
				(width 0.1524)
				(type default)
			)
			(layer "B.SilkS")
		)
		(fp_line
			(start -2.54 3.81)
			(end -2.54 3.6703)
			(stroke
				(width 0.1524)
				(type default)
			)
			(layer "B.SilkS")
		)
		(fp_line
			(start 0 -1.27)
			(end 0 -0.635)
			(stroke
				(width 0.1524)
				(type default)
			)
			(layer "B.SilkS")
		)
		(fp_line
			(start 0 0.635)
			(end 0 1.905)
			(stroke
				(width 0.1524)
				(type default)
			)
			(layer "B.SilkS")
		)
		(fp_line
			(start 0 3.175)
			(end 0 3.81)
			(stroke
				(width 0.1524)
				(type default)
			)
			(layer "B.SilkS")
		)
		(fp_line
			(start 0 3.81)
			(end -2.54 3.81)
			(stroke
				(width 0.1524)
				(type default)
			)
			(layer "B.SilkS")
		)
		(fp_poly
			(pts
				(xy 0.761746 0) (xy 2.285746 -0.762) (xy 2.285746 0.762)
			)
			(stroke
				(width 0)
				(type default)
			)
			(fill yes)
			(layer "B.SilkS")
		)
		(fp_line
			(start -2.54 -1.27)
			(end 0 -1.27)
			(stroke
				(width 0.1)
				(type default)
			)
			(layer "B.Fab")
		)
		(fp_line
			(start -2.54 3.81)
			(end -2.54 -1.27)
			(stroke
				(width 0.1)
				(type default)
			)
			(layer "B.Fab")
		)
		(fp_line
			(start 0 -1.27)
			(end 0 3.81)
			(stroke
				(width 0.1)
				(type default)
			)
			(layer "B.Fab")
		)
		(fp_line
			(start 0 3.81)
			(end -2.54 3.81)
			(stroke
				(width 0.1)
				(type default)
			)
			(layer "B.Fab")
		)
		(fp_poly
			(pts
				(xy 0.761746 0) (xy 2.285746 -0.762) (xy 2.285746 0.762)
			)
			(stroke
				(width 0)
				(type default)
			)
			(fill yes)
			(layer "B.Fab")
		)
		(pad "1" thru_hole circle
			(at 0 0 180)
			(size 1.0033 1.0033)
			(drill 0.249936)
			(layers "*.Cu" "*.Mask")
			(remove_unused_layers no)
			(net "TDR_DIFF_85_IN5_DIP")
			(clearance 0.10795)
			(padstack
				(mode front_inner_back)
				(layer "Inner"
					(shape circle)
					(size 0.8001 0.8001)
					(clearance 0.1524)
				)
				(layer "B.Cu"
					(shape circle)
					(size 1.0033 1.0033)
					(thermal_gap 0.10795)
					(clearance 0.10795)
				)
			)
		)
		(pad "2" thru_hole circle
			(at -2.54 0 180)
			(size 1.9939 1.9939)
			(drill 0.249936)
			(layers "*.Cu" "*.Mask")
			(remove_unused_layers no)
			(net "COUPON_GND1")
			(clearance 0.10795)
			(padstack
				(mode front_inner_back)
				(layer "Inner"
					(shape circle)
					(size 0.8001 0.8001)
					(clearance 0.1524)
				)
				(layer "B.Cu"
					(shape circle)
					(size 1.9939 1.9939)
					(thermal_gap 0.10795)
					(clearance 0.10795)
				)
			)
		)
		(pad "3" thru_hole circle
			(at -2.54 2.54 180)
			(size 1.9939 1.9939)
			(drill 0.249936)
			(layers "*.Cu" "*.Mask")
			(remove_unused_layers no)
			(net "COUPON_GND1")
			(clearance 0.10795)
			(padstack
				(mode front_inner_back)
				(layer "Inner"
					(shape circle)
					(size 0.8001 0.8001)
					(clearance 0.1524)
				)
				(layer "B.Cu"
					(shape circle)
					(size 1.9939 1.9939)
					(thermal_gap 0.10795)
					(clearance 0.10795)
				)
			)
		)
		(pad "4" thru_hole circle
			(at 0 2.54 180)
			(size 1.0033 1.0033)
			(drill 0.249936)
			(layers "*.Cu" "*.Mask")
			(remove_unused_layers no)
			(net "TDR_DIFF_85_IN5_DIN")
			(clearance 0.10795)
			(padstack
				(mode front_inner_back)
				(layer "Inner"
					(shape circle)
					(size 0.8001 0.8001)
					(clearance 0.1524)
				)
				(layer "B.Cu"
					(shape circle)
					(size 1.0033 1.0033)
					(thermal_gap 0.10795)
					(clearance 0.10795)
				)
			)
		)
	)
	(footprint ""
		(layer "B.Cu")
		(at 284.669992 -305.399948 -90)
		(property "Reference" "C3333"
			(at 0 0 90)
			(layer "B.SilkS")
			(hide yes)
			(effects
				(font
					(size 1.27 1.27)
				)
				(justify mirror)
			)
		)
		(property "Value" ""
			(at 0 0 90)
			(layer "B.Fab")
			(effects
				(font
					(size 1.27 1.27)
				)
				(justify mirror)
			)
		)
		(duplicate_pad_numbers_are_jumpers no)
		(fp_line
			(start -0.299974 0.150114)
			(end 0.299974 0.150114)
			(stroke
				(width 0.1)
				(type default)
			)
			(layer "B.Fab")
		)
		(fp_line
			(start 0.299974 0.150114)
			(end 0.299974 -0.150114)
			(stroke
				(width 0.1)
				(type default)
			)
			(layer "B.Fab")
		)
		(fp_line
			(start -0.299974 -0.150114)
			(end -0.299974 0.150114)
			(stroke
				(width 0.1)
				(type default)
			)
			(layer "B.Fab")
		)
		(fp_line
			(start 0.299974 -0.150114)
			(end -0.299974 -0.150114)
			(stroke
				(width 0.1)
				(type default)
			)
			(layer "B.Fab")
		)
		(pad "1" smd rect
			(at 0.2667 0 90)
			(size 0.3048 0.381)
			(layers "B.Cu" "B.Mask" "B.Paste")
			(net "P1V25_SERDES_VDDPLL_PEX2")
		)
		(pad "2" smd rect
			(at -0.2667 0 90)
			(size 0.3048 0.381)
			(layers "B.Cu" "B.Mask" "B.Paste")
			(net "GND")
		)
	)
	(footprint ""
		(layer "B.Cu")
		(at 262.979408 -84.713826)
		(property "Reference" "C2647"
			(at 0 0 0)
			(layer "B.SilkS")
			(hide yes)
			(effects
				(font
					(size 1.27 1.27)
				)
				(justify mirror)
			)
		)
		(property "Value" ""
			(at 0 0 0)
			(layer "B.Fab")
			(effects
				(font
					(size 1.27 1.27)
				)
				(justify mirror)
			)
		)
		(duplicate_pad_numbers_are_jumpers no)
		(fp_line
			(start -0.7874 -0.4064)
			(end -0.7874 0.4064)
			(stroke
				(width 0.1524)
				(type default)
			)
			(layer "B.SilkS")
		)
		(fp_line
			(start -0.7874 0.4064)
			(end 0.7874 0.4064)
			(stroke
				(width 0.1524)
				(type default)
			)
			(layer "B.SilkS")
		)
		(fp_line
			(start 0.7874 -0.4064)
			(end -0.7874 -0.4064)
			(stroke
				(width 0.1524)
				(type default)
			)
			(layer "B.SilkS")
		)
		(fp_line
			(start 0.7874 0.4064)
			(end 0.7874 -0.4064)
			(stroke
				(width 0.1524)
				(type default)
			)
			(layer "B.SilkS")
		)
		(fp_line
			(start -0.67945 -0.3048)
			(end -0.67945 0.3048)
			(stroke
				(width 0.1)
				(type default)
			)
			(layer "B.Fab")
		)
		(fp_line
			(start -0.67945 0.3048)
			(end -0.120396 0.3048)
			(stroke
				(width 0.1)
				(type default)
			)
			(layer "B.Fab")
		)
		(fp_line
			(start -0.12065 -0.3048)
			(end -0.67945 -0.3048)
			(stroke
				(width 0.1)
				(type default)
			)
			(layer "B.Fab")
		)
		(fp_line
			(start -0.12065 -0.2794)
			(end -0.12065 -0.3048)
			(stroke
				(width 0.1)
				(type default)
			)
			(layer "B.Fab")
		)
		(fp_line
			(start -0.120396 0.2794)
			(end 0.12065 0.2794)
			(stroke
				(width 0.1)
				(type default)
			)
			(layer "B.Fab")
		)
		(fp_line
			(start -0.120396 0.3048)
			(end -0.120396 0.2794)
			(stroke
				(width 0.1)
				(type default)
			)
			(layer "B.Fab")
		)
		(fp_line
			(start 0.12065 -0.305054)
			(end 0.12065 -0.2794)
			(stroke
				(width 0.1)
				(type default)
			)
			(layer "B.Fab")
		)
		(fp_line
			(start 0.12065 -0.2794)
			(end -0.12065 -0.2794)
			(stroke
				(width 0.1)
				(type default)
			)
			(layer "B.Fab")
		)
		(fp_line
			(start 0.12065 0.2794)
			(end 0.12065 0.3048)
			(stroke
				(width 0.1)
				(type default)
			)
			(layer "B.Fab")
		)
		(fp_line
			(start 0.12065 0.3048)
			(end 0.67945 0.3048)
			(stroke
				(width 0.1)
				(type default)
			)
			(layer "B.Fab")
		)
		(fp_line
			(start 0.67945 -0.305054)
			(end 0.12065 -0.305054)
			(stroke
				(width 0.1)
				(type default)
			)
			(layer "B.Fab")
		)
		(fp_line
			(start 0.67945 0.3048)
			(end 0.67945 -0.305054)
			(stroke
				(width 0.1)
				(type default)
			)
			(layer "B.Fab")
		)
		(pad "1" smd circle
			(at 0.40005 0 180)
			(size 0 0)
			(layers "B.Cu" "B.Mask" "B.Paste")
			(net "P3V3_CLK_GEN_VDDMXCK_CK440")
		)
		(pad "2" smd circle
			(at -0.40005 0 180)
			(size 0 0)
			(layers "B.Cu" "B.Mask" "B.Paste")
			(net "GND")
		)
	)
	(footprint ""
		(layer "B.Cu")
		(at 247.099582 -227.965 180)
		(property "Reference" "R3488"
			(at 0 0 0)
			(layer "B.SilkS")
			(hide yes)
			(effects
				(font
					(size 1.27 1.27)
				)
				(justify mirror)
			)
		)
		(property "Value" ""
			(at 0 0 0)
			(layer "B.Fab")
			(effects
				(font
					(size 1.27 1.27)
				)
				(justify mirror)
			)
		)
		(duplicate_pad_numbers_are_jumpers no)
		(fp_line
			(start 0.7874 0.4064)
			(end 0.7874 -0.4064)
			(stroke
				(width 0.1524)
				(type default)
			)
			(layer "B.SilkS")
		)
		(fp_line
			(start 0.7874 -0.4064)
			(end -0.7874 -0.4064)
			(stroke
				(width 0.1524)
				(type default)
			)
			(layer "B.SilkS")
		)
		(fp_line
			(start -0.7874 0.4064)
			(end 0.7874 0.4064)
			(stroke
				(width 0.1524)
				(type default)
			)
			(layer "B.SilkS")
		)
		(fp_line
			(start -0.7874 -0.4064)
			(end -0.7874 0.4064)
			(stroke
				(width 0.1524)
				(type default)
			)
			(layer "B.SilkS")
		)
		(fp_line
			(start 0.67945 0.3048)
			(end 0.67945 -0.305054)
			(stroke
				(width 0.1)
				(type default)
			)
			(layer "B.Fab")
		)
		(fp_line
			(start 0.67945 -0.305054)
			(end 0.12065 -0.305054)
			(stroke
				(width 0.1)
				(type default)
			)
			(layer "B.Fab")
		)
		(fp_line
			(start 0.12065 0.3048)
			(end 0.67945 0.3048)
			(stroke
				(width 0.1)
				(type default)
			)
			(layer "B.Fab")
		)
		(fp_line
			(start 0.12065 0.2794)
			(end 0.12065 0.3048)
			(stroke
				(width 0.1)
				(type default)
			)
			(layer "B.Fab")
		)
		(fp_line
			(start 0.12065 -0.2794)
			(end -0.12065 -0.2794)
			(stroke
				(width 0.1)
				(type default)
			)
			(layer "B.Fab")
		)
		(fp_line
			(start 0.12065 -0.305054)
			(end 0.12065 -0.2794)
			(stroke
				(width 0.1)
				(type default)
			)
			(layer "B.Fab")
		)
		(fp_line
			(start -0.120396 0.3048)
			(end -0.120396 0.2794)
			(stroke
				(width 0.1)
				(type default)
			)
			(layer "B.Fab")
		)
		(fp_line
			(start -0.120396 0.2794)
			(end 0.12065 0.2794)
			(stroke
				(width 0.1)
				(type default)
			)
			(layer "B.Fab")
		)
		(fp_line
			(start -0.12065 -0.2794)
			(end -0.12065 -0.3048)
			(stroke
				(width 0.1)
				(type default)
			)
			(layer "B.Fab")
		)
		(fp_line
			(start -0.12065 -0.3048)
			(end -0.67945 -0.3048)
			(stroke
				(width 0.1)
				(type default)
			)
			(layer "B.Fab")
		)
		(fp_line
			(start -0.67945 0.3048)
			(end -0.120396 0.3048)
			(stroke
				(width 0.1)
				(type default)
			)
			(layer "B.Fab")
		)
		(fp_line
			(start -0.67945 -0.3048)
			(end -0.67945 0.3048)
			(stroke
				(width 0.1)
				(type default)
			)
			(layer "B.Fab")
		)
		(pad "1" smd circle
			(at 0.40005 0)
			(size 0 0)
			(layers "B.Cu" "B.Mask" "B.Paste")
			(net "SPI_PEX2_SDIO2_R1")
		)
		(pad "2" smd circle
			(at -0.40005 0)
			(size 0 0)
			(layers "B.Cu" "B.Mask" "B.Paste")
			(net "GND")
		)
	)
	(footprint ""
		(layer "B.Cu")
		(at 394.65504 -294.4749)
		(property "Reference" "C3566"
			(at 0 0 0)
			(layer "B.SilkS")
			(hide yes)
			(effects
				(font
					(size 1.27 1.27)
				)
				(justify mirror)
			)
		)
		(property "Value" ""
			(at 0 0 0)
			(layer "B.Fab")
			(effects
				(font
					(size 1.27 1.27)
				)
				(justify mirror)
			)
		)
		(duplicate_pad_numbers_are_jumpers no)
		(fp_line
			(start -0.299974 -0.150114)
			(end -0.299974 0.150114)
			(stroke
				(width 0.1)
				(type default)
			)
			(layer "B.Fab")
		)
		(fp_line
			(start -0.299974 0.150114)
			(end 0.299974 0.150114)
			(stroke
				(width 0.1)
				(type default)
			)
			(layer "B.Fab")
		)
		(fp_line
			(start 0.299974 -0.150114)
			(end -0.299974 -0.150114)
			(stroke
				(width 0.1)
				(type default)
			)
			(layer "B.Fab")
		)
		(fp_line
			(start 0.299974 0.150114)
			(end 0.299974 -0.150114)
			(stroke
				(width 0.1)
				(type default)
			)
			(layer "B.Fab")
		)
		(pad "1" smd rect
			(at 0.2667 0 180)
			(size 0.3048 0.381)
			(layers "B.Cu" "B.Mask" "B.Paste")
			(net "PCEPLL4_VDDA18_PEX3")
		)
		(pad "2" smd rect
			(at -0.2667 0 180)
			(size 0.3048 0.381)
			(layers "B.Cu" "B.Mask" "B.Paste")
			(net "GND")
		)
	)
	(footprint ""
		(layer "B.Cu")
		(at 174.800006 -288.299906 90)
		(property "Reference" "C3096"
			(at 0 0 90)
			(layer "B.SilkS")
			(hide yes)
			(effects
				(font
					(size 1.27 1.27)
				)
				(justify mirror)
			)
		)
		(property "Value" ""
			(at 0 0 90)
			(layer "B.Fab")
			(effects
				(font
					(size 1.27 1.27)
				)
				(justify mirror)
			)
		)
		(duplicate_pad_numbers_are_jumpers no)
		(fp_line
			(start 0.299974 -0.150114)
			(end -0.299974 -0.150114)
			(stroke
				(width 0.1)
				(type default)
			)
			(layer "B.Fab")
		)
		(fp_line
			(start -0.299974 -0.150114)
			(end -0.299974 0.150114)
			(stroke
				(width 0.1)
				(type default)
			)
			(layer "B.Fab")
		)
		(fp_line
			(start 0.299974 0.150114)
			(end 0.299974 -0.150114)
			(stroke
				(width 0.1)
				(type default)
			)
			(layer "B.Fab")
		)
		(fp_line
			(start -0.299974 0.150114)
			(end 0.299974 0.150114)
			(stroke
				(width 0.1)
				(type default)
			)
			(layer "B.Fab")
		)
		(pad "1" smd rect
			(at 0.2667 0 270)
			(size 0.3048 0.381)
			(layers "B.Cu" "B.Mask" "B.Paste")
			(net "P1V25_PEX1")
		)
		(pad "2" smd rect
			(at -0.2667 0 270)
			(size 0.3048 0.381)
			(layers "B.Cu" "B.Mask" "B.Paste")
			(net "GND")
		)
	)
)
